# S9S_MB_2U (Grand Teton) — schematic netlist excerpt (pin names and nets, part order shuffled) for the footprints in the layout excerpt that follows; sources: Cadence DE-HDL packaged netlist, KiCad conversion of 03242023_DA0F0TMBIJ0_F0T_Motherboard_J_brd_V01_OCP.brd

C1182  Q_CAP  22UF 4V 20% X6S  pkg C0603  page 189 : A = P1V05_PCH_AUX ; B = GND
R2332  Q_RES  2K 1% CHIP  pkg 0402LF  page 281 : A = FM_PVPP_HBM_CPU0_EN ; B = GND
C477  Q_CAP  47UF 4V 20% X6S  pkg C0805  page 79 : A = PVCCFA_EHV_FIVRA_CPU1 ; B = GND

(kicad_pcb
	(version 20260206)
	(generator "pcbnew")
	(generator_version "10.0")
	(general
		(thickness 1.6)
		(legacy_teardrops no)
	)
	(paper "A4")
	(title_block
		(title "03242023_DA0F0TMBIJ0_F0T_Motherboard_J_brd_V01_OCP.brd")
		(comment 1 "Grand Teton / footprints 5794-5796 of 6105")
	)
	(layers
		(0 "F.Cu" signal "TOP")
		(4 "In1.Cu" signal "GND")
		(6 "In2.Cu" signal "IN1")
		(8 "In3.Cu" signal "GND1")
		(10 "In4.Cu" signal "IN2")
		(12 "In5.Cu" signal "GND2")
		(14 "In6.Cu" signal "IN3")
		(16 "In7.Cu" signal "GND3")
		(18 "In8.Cu" signal "VCC")
		(20 "In9.Cu" signal "VCC1")
		(22 "In10.Cu" signal "GND4")
		(24 "In11.Cu" signal "IN4")
		(26 "In12.Cu" signal "GND5")
		(28 "In13.Cu" signal "IN5")
		(30 "In14.Cu" signal "GND6")
		(32 "In15.Cu" signal "IN6")
		(34 "In16.Cu" signal "GND7")
		(2 "B.Cu" signal "BOTTOM")
		(9 "F.Adhes" user "F.Adhesive")
		(11 "B.Adhes" user "B.Adhesive")
		(13 "F.Paste" user "Package Geometry/Pastemask Top")
		(15 "B.Paste" user "Package Geometry/Pastemask Bottom")
		(5 "F.SilkS" user "Ref Des/Silkscreen Top")
		(7 "B.SilkS" user "Ref Des/Silkscreen Bottom")
		(1 "F.Mask" user "Board Geometry/Soldermask Top")
		(3 "B.Mask" user "Board Geometry/Soldermask Bottom")
		(17 "Dwgs.User" user "User.Drawings")
		(19 "Cmts.User" user "User.Comments")
		(21 "Eco1.User" user "User.Eco1")
		(23 "Eco2.User" user "User.Eco2")
		(25 "Edge.Cuts" user "Board Geometry/Outline")
		(27 "Margin" user)
		(31 "F.CrtYd" user "Package Geometry/Place Bound Top")
		(29 "B.CrtYd" user "Package Geometry/Place Bound Bottom")
		(35 "F.Fab" user "Ref Des/Assembly Top")
		(33 "B.Fab" user "Ref Des/Assembly Bottom")
	)
	(footprint ""
		(layer "B.Cu")
		(at 297.44416 -52.283868)
		(property "Reference" "C1182"
			(at 0 0 0)
			(layer "B.SilkS")
			(hide yes)
			(effects
				(font
					(size 1.27 1.27)
				)
				(justify mirror)
			)
		)
		(property "Value" ""
			(at 0 0 0)
			(layer "B.Fab")
			(effects
				(font
					(size 1.27 1.27)
				)
				(justify mirror)
			)
		)
		(duplicate_pad_numbers_are_jumpers no)
		(fp_line
			(start -1.2954 -0.5842)
			(end -1.2954 0.5842)
			(stroke
				(width 0.1524)
				(type default)
			)
			(layer "B.SilkS")
		)
		(fp_line
			(start -1.2954 0.5842)
			(end 1.2954 0.5842)
			(stroke
				(width 0.1524)
				(type default)
			)
			(layer "B.SilkS")
		)
		(fp_line
			(start 0 -0.5842)
			(end 0 0.5842)
			(stroke
				(width 0.1524)
				(type default)
			)
			(layer "B.SilkS")
		)
		(fp_line
			(start 1.2954 -0.5842)
			(end -1.2954 -0.5842)
			(stroke
				(width 0.1524)
				(type default)
			)
			(layer "B.SilkS")
		)
		(fp_line
			(start 1.2954 0.5842)
			(end 1.2954 -0.5842)
			(stroke
				(width 0.1524)
				(type default)
			)
			(layer "B.SilkS")
		)
		(fp_line
			(start -1.1938 -0.4064)
			(end -1.1938 0.4064)
			(stroke
				(width 0.1)
				(type default)
			)
			(layer "B.Fab")
		)
		(fp_line
			(start -1.1938 0.4064)
			(end -0.8636 0.4064)
			(stroke
				(width 0.1)
				(type default)
			)
			(layer "B.Fab")
		)
		(fp_line
			(start -0.8636 -0.4572)
			(end -0.8636 -0.4064)
			(stroke
				(width 0.1)
				(type default)
			)
			(layer "B.Fab")
		)
		(fp_line
			(start -0.8636 -0.4064)
			(end -1.1938 -0.4064)
			(stroke
				(width 0.1)
				(type default)
			)
			(layer "B.Fab")
		)
		(fp_line
			(start -0.8636 0.4064)
			(end -0.8636 0.4572)
			(stroke
				(width 0.1)
				(type default)
			)
			(layer "B.Fab")
		)
		(fp_line
			(start -0.8636 0.4572)
			(end 0.8636 0.4572)
			(stroke
				(width 0.1)
				(type default)
			)
			(layer "B.Fab")
		)
		(fp_line
			(start 0.8636 -0.4572)
			(end -0.8636 -0.4572)
			(stroke
				(width 0.1)
				(type default)
			)
			(layer "B.Fab")
		)
		(fp_line
			(start 0.8636 -0.4064)
			(end 0.8636 -0.4572)
			(stroke
				(width 0.1)
				(type default)
			)
			(layer "B.Fab")
		)
		(fp_line
			(start 0.8636 0.4064)
			(end 1.1938 0.4064)
			(stroke
				(width 0.1)
				(type default)
			)
			(layer "B.Fab")
		)
		(fp_line
			(start 0.8636 0.4572)
			(end 0.8636 0.4064)
			(stroke
				(width 0.1)
				(type default)
			)
			(layer "B.Fab")
		)
		(fp_line
			(start 1.1938 -0.4064)
			(end 0.8636 -0.4064)
			(stroke
				(width 0.1)
				(type default)
			)
			(layer "B.Fab")
		)
		(fp_line
			(start 1.1938 0.4064)
			(end 1.1938 -0.4064)
			(stroke
				(width 0.1)
				(type default)
			)
			(layer "B.Fab")
		)
		(pad "1" smd rect
			(at 0.7366 0 270)
			(size 0.7112 0.8128)
			(layers "B.Cu" "B.Mask" "B.Paste")
			(net "P1V05_PCH_AUX")
		)
		(pad "2" smd rect
			(at -0.7366 0 270)
			(size 0.7112 0.8128)
			(layers "B.Cu" "B.Mask" "B.Paste")
			(net "GND")
		)
	)
	(footprint ""
		(layer "B.Cu")
		(at 158.84017 -250.58243 90)
		(property "Reference" "C477"
			(at 0 0 90)
			(layer "B.SilkS")
			(hide yes)
			(effects
				(font
					(size 1.27 1.27)
				)
				(justify mirror)
			)
		)
		(property "Value" ""
			(at 0 0 90)
			(layer "B.Fab")
			(effects
				(font
					(size 1.27 1.27)
				)
				(justify mirror)
			)
		)
		(duplicate_pad_numbers_are_jumpers no)
		(fp_line
			(start 1.524 -0.762)
			(end -1.524 -0.762)
			(stroke
				(width 0.1524)
				(type default)
			)
			(layer "B.SilkS")
		)
		(fp_line
			(start -1.524 -0.762)
			(end -1.524 0.762)
			(stroke
				(width 0.1524)
				(type default)
			)
			(layer "B.SilkS")
		)
		(fp_line
			(start 1.524 0.762)
			(end 1.524 -0.762)
			(stroke
				(width 0.1524)
				(type default)
			)
			(layer "B.SilkS")
		)
		(fp_line
			(start -1.524 0.762)
			(end 1.524 0.762)
			(stroke
				(width 0.1524)
				(type default)
			)
			(layer "B.SilkS")
		)
		(fp_line
			(start 1.1049 -0.724916)
			(end 1.1049 0.724916)
			(stroke
				(width 0.1)
				(type default)
			)
			(layer "B.Fab")
		)
		(fp_line
			(start -1.1049 -0.724916)
			(end 1.1049 -0.724916)
			(stroke
				(width 0.1)
				(type default)
			)
			(layer "B.Fab")
		)
		(fp_line
			(start 1.1049 0.724916)
			(end -1.1049 0.724916)
			(stroke
				(width 0.1)
				(type default)
			)
			(layer "B.Fab")
		)
		(fp_line
			(start -1.1049 0.724916)
			(end -1.1049 -0.724916)
			(stroke
				(width 0.1)
				(type default)
			)
			(layer "B.Fab")
		)
		(pad "1" smd rect
			(at 0.889 0 90)
			(size 1.016 1.27)
			(layers "B.Cu" "B.Mask" "B.Paste")
			(net "PVCCFA_EHV_FIVRA_CPU1")
		)
		(pad "2" smd rect
			(at -0.889 0 90)
			(size 1.016 1.27)
			(layers "B.Cu" "B.Mask" "B.Paste")
			(net "GND")
		)
	)
	(footprint ""
		(layer "B.Cu")
		(at 370.695474 -354.93833 90)
		(property "Reference" "R2332"
			(at 0 0 90)
			(layer "B.SilkS")
			(hide yes)
			(effects
				(font
					(size 1.27 1.27)
				)
				(justify mirror)
			)
		)
		(property "Value" ""
			(at 0 0 90)
			(layer "B.Fab")
			(effects
				(font
					(size 1.27 1.27)
				)
				(justify mirror)
			)
		)
		(duplicate_pad_numbers_are_jumpers no)
		(fp_line
			(start 0.7874 -0.4064)
			(end -0.7874 -0.4064)
			(stroke
				(width 0.1524)
				(type default)
			)
			(layer "B.SilkS")
		)
		(fp_line
			(start -0.7874 -0.4064)
			(end -0.7874 0.4064)
			(stroke
				(width 0.1524)
				(type default)
			)
			(layer "B.SilkS")
		)
		(fp_line
			(start 0.7874 0.4064)
			(end 0.7874 -0.4064)
			(stroke
				(width 0.1524)
				(type default)
			)
			(layer "B.SilkS")
		)
		(fp_line
			(start -0.7874 0.4064)
			(end 0.7874 0.4064)
			(stroke
				(width 0.1524)
				(type default)
			)
			(layer "B.SilkS")
		)
		(fp_line
			(start 0.67945 -0.305054)
			(end 0.12065 -0.305054)
			(stroke
				(width 0.1)
				(type default)
			)
			(layer "B.Fab")
		)
		(fp_line
			(start 0.12065 -0.305054)
			(end 0.12065 -0.2794)
			(stroke
				(width 0.1)
				(type default)
			)
			(layer "B.Fab")
		)
		(fp_line
			(start -0.12065 -0.3048)
			(end -0.67945 -0.3048)
			(stroke
				(width 0.1)
				(type default)
			)
			(layer "B.Fab")
		)
		(fp_line
			(start -0.67945 -0.3048)
			(end -0.67945 0.3048)
			(stroke
				(width 0.1)
				(type default)
			)
			(layer "B.Fab")
		)
		(fp_line
			(start 0.12065 -0.2794)
			(end -0.12065 -0.2794)
			(stroke
				(width 0.1)
				(type default)
			)
			(layer "B.Fab")
		)
		(fp_line
			(start -0.12065 -0.2794)
			(end -0.12065 -0.3048)
			(stroke
				(width 0.1)
				(type default)
			)
			(layer "B.Fab")
		)
		(fp_line
			(start 0.12065 0.2794)
			(end 0.12065 0.3048)
			(stroke
				(width 0.1)
				(type default)
			)
			(layer "B.Fab")
		)
		(fp_line
			(start -0.120396 0.2794)
			(end 0.12065 0.2794)
			(stroke
				(width 0.1)
				(type default)
			)
			(layer "B.Fab")
		)
		(fp_line
			(start 0.67945 0.3048)
			(end 0.67945 -0.305054)
			(stroke
				(width 0.1)
				(type default)
			)
			(layer "B.Fab")
		)
		(fp_line
			(start 0.12065 0.3048)
			(end 0.67945 0.3048)
			(stroke
				(width 0.1)
				(type default)
			)
			(layer "B.Fab")
		)
		(fp_line
			(start -0.120396 0.3048)
			(end -0.120396 0.2794)
			(stroke
				(width 0.1)
				(type default)
			)
			(layer "B.Fab")
		)
		(fp_line
			(start -0.67945 0.3048)
			(end -0.120396 0.3048)
			(stroke
				(width 0.1)
				(type default)
			)
			(layer "B.Fab")
		)
		(pad "1" smd circle
			(at 0.40005 0 270)
			(size 0 0)
			(layers "B.Cu" "B.Mask" "B.Paste")
			(net "FM_PVPP_HBM_CPU0_EN")
		)
		(pad "2" smd circle
			(at -0.40005 0 270)
			(size 0 0)
			(layers "B.Cu" "B.Mask" "B.Paste")
			(net "GND")
		)
	)
)
